FILE_TYPE=LIBRARY_PARTS;
primitive 'SCONN64_H87568002_A','SCONN64_H87568002_A_SMT';
  pin
    'IO1':
      PIN_NUMBER='(1)';
      BIDIRECTIONAL='TRUE';
      INPUT_LOAD='(-0.01,0.01)';
      OUTPUT_LOAD='(1.0,-1.0)';
    'IO10':
      PIN_NUMBER='(10)';
      BIDIRECTIONAL='TRUE';
      INPUT_LOAD='(-0.01,0.01)';
      OUTPUT_LOAD='(1.0,-1.0)';
    'IO11':
      PIN_NUMBER='(11)';
      BIDIRECTIONAL='TRUE';
      INPUT_LOAD='(-0.01,0.01)';
      OUTPUT_LOAD='(1.0,-1.0)';
    'IO12':
      PIN_NUMBER='(12)';
      BIDIRECTIONAL='TRUE';
      INPUT_LOAD='(-0.01,0.01)';
      OUTPUT_LOAD='(1.0,-1.0)';
    'IO13':
      PIN_NUMBER='(13)';
      BIDIRECTIONAL='TRUE';
      INPUT_LOAD='(-0.01,0.01)';
      OUTPUT_LOAD='(1.0,-1.0)';
    'IO14':
      PIN_NUMBER='(14)';
      BIDIRECTIONAL='TRUE';
      INPUT_LOAD='(-0.01,0.01)';
      OUTPUT_LOAD='(1.0,-1.0)';
    'IO15':
      PIN_NUMBER='(15)';
      BIDIRECTIONAL='TRUE';
      INPUT_LOAD='(-0.01,0.01)';
      OUTPUT_LOAD='(1.0,-1.0)';
    'IO16':
      PIN_NUMBER='(16)';
      BIDIRECTIONAL='TRUE';
      INPUT_LOAD='(-0.01,0.01)';
      OUTPUT_LOAD='(1.0,-1.0)';
    'IO17':
      PIN_NUMBER='(17)';
      BIDIRECTIONAL='TRUE';
      INPUT_LOAD='(-0.01,0.01)';
      OUTPUT_LOAD='(1.0,-1.0)';
    'IO18':
      PIN_NUMBER='(18)';
      BIDIRECTIONAL='TRUE';
      INPUT_LOAD='(-0.01,0.01)';
      OUTPUT_LOAD='(1.0,-1.0)';
    'IO19':
      PIN_NUMBER='(19)';
      BIDIRECTIONAL='TRUE';
      INPUT_LOAD='(-0.01,0.01)';
      OUTPUT_LOAD='(1.0,-1.0)';
    'IO2':
      PIN_NUMBER='(2)';
      BIDIRECTIONAL='TRUE';
      INPUT_LOAD='(-0.01,0.01)';
      OUTPUT_LOAD='(1.0,-1.0)';
    'IO20':
      PIN_NUMBER='(20)';
      BIDIRECTIONAL='TRUE';
      INPUT_LOAD='(-0.01,0.01)';
      OUTPUT_LOAD='(1.0,-1.0)';
    'IO21':
      PIN_NUMBER='(21)';
      BIDIRECTIONAL='TRUE';
      INPUT_LOAD='(-0.01,0.01)';
      OUTPUT_LOAD='(1.0,-1.0)';
    'IO22':
      PIN_NUMBER='(22)';
      BIDIRECTIONAL='TRUE';
      INPUT_LOAD='(-0.01,0.01)';
      OUTPUT_LOAD='(1.0,-1.0)';
    'IO23':
      PIN_NUMBER='(23)';
      BIDIRECTIONAL='TRUE';
      INPUT_LOAD='(-0.01,0.01)';
      OUTPUT_LOAD='(1.0,-1.0)';
    'IO24':
      PIN_NUMBER='(24)';
      BIDIRECTIONAL='TRUE';
      INPUT_LOAD='(-0.01,0.01)';
      OUTPUT_LOAD='(1.0,-1.0)';
    'IO25':
      PIN_NUMBER='(25)';
      BIDIRECTIONAL='TRUE';
      INPUT_LOAD='(-0.01,0.01)';
      OUTPUT_LOAD='(1.0,-1.0)';
    'IO26':
      PIN_NUMBER='(26)';
      BIDIRECTIONAL='TRUE';
      INPUT_LOAD='(-0.01,0.01)';
      OUTPUT_LOAD='(1.0,-1.0)';
    'IO27':
      PIN_NUMBER='(27)';
      BIDIRECTIONAL='TRUE';
      INPUT_LOAD='(-0.01,0.01)';
      OUTPUT_LOAD='(1.0,-1.0)';
    'IO28':
      PIN_NUMBER='(28)';
      BIDIRECTIONAL='TRUE';
      INPUT_LOAD='(-0.01,0.01)';
      OUTPUT_LOAD='(1.0,-1.0)';
    'IO29':
      PIN_NUMBER='(29)';
      BIDIRECTIONAL='TRUE';
      INPUT_LOAD='(-0.01,0.01)';
      OUTPUT_LOAD='(1.0,-1.0)';
    'IO3':
      PIN_NUMBER='(3)';
      BIDIRECTIONAL='TRUE';
      INPUT_LOAD='(-0.01,0.01)';
      OUTPUT_LOAD='(1.0,-1.0)';
    'IO30':
      PIN_NUMBER='(30)';
      BIDIRECTIONAL='TRUE';
      INPUT_LOAD='(-0.01,0.01)';
      OUTPUT_LOAD='(1.0,-1.0)';
    'IO31':
      PIN_NUMBER='(31)';
      BIDIRECTIONAL='TRUE';
      INPUT_LOAD='(-0.01,0.01)';
      OUTPUT_LOAD='(1.0,-1.0)';
    'IO32':
      PIN_NUMBER='(32)';
      BIDIRECTIONAL='TRUE';
      INPUT_LOAD='(-0.01,0.01)';
      OUTPUT_LOAD='(1.0,-1.0)';
    'IO33':
      PIN_NUMBER='(33)';
      BIDIRECTIONAL='TRUE';
      INPUT_LOAD='(-0.01,0.01)';
      OUTPUT_LOAD='(1.0,-1.0)';
    'IO34':
      PIN_NUMBER='(34)';
      BIDIRECTIONAL='TRUE';
      INPUT_LOAD='(-0.01,0.01)';
      OUTPUT_LOAD='(1.0,-1.0)';
    'IO35':
      PIN_NUMBER='(35)';
      BIDIRECTIONAL='TRUE';
      INPUT_LOAD='(-0.01,0.01)';
      OUTPUT_LOAD='(1.0,-1.0)';
    'IO36':
      PIN_NUMBER='(36)';
      BIDIRECTIONAL='TRUE';
      INPUT_LOAD='(-0.01,0.01)';
      OUTPUT_LOAD='(1.0,-1.0)';
    'IO37':
      PIN_NUMBER='(37)';
      BIDIRECTIONAL='TRUE';
      INPUT_LOAD='(-0.01,0.01)';
      OUTPUT_LOAD='(1.0,-1.0)';
    'IO38':
      PIN_NUMBER='(38)';
      BIDIRECTIONAL='TRUE';
      INPUT_LOAD='(-0.01,0.01)';
      OUTPUT_LOAD='(1.0,-1.0)';
    'IO39':
      PIN_NUMBER='(39)';
      BIDIRECTIONAL='TRUE';
      INPUT_LOAD='(-0.01,0.01)';
      OUTPUT_LOAD='(1.0,-1.0)';
    'IO4':
      PIN_NUMBER='(4)';
      BIDIRECTIONAL='TRUE';
      INPUT_LOAD='(-0.01,0.01)';
      OUTPUT_LOAD='(1.0,-1.0)';
    'IO40':
      PIN_NUMBER='(40)';
      BIDIRECTIONAL='TRUE';
      INPUT_LOAD='(-0.01,0.01)';
      OUTPUT_LOAD='(1.0,-1.0)';
    'IO41':
      PIN_NUMBER='(41)';
      BIDIRECTIONAL='TRUE';
      INPUT_LOAD='(-0.01,0.01)';
      OUTPUT_LOAD='(1.0,-1.0)';
    'IO42':
      PIN_NUMBER='(42)';
      BIDIRECTIONAL='TRUE';
      INPUT_LOAD='(-0.01,0.01)';
      OUTPUT_LOAD='(1.0,-1.0)';
    'IO43':
      PIN_NUMBER='(43)';
      BIDIRECTIONAL='TRUE';
      INPUT_LOAD='(-0.01,0.01)';
      OUTPUT_LOAD='(1.0,-1.0)';
    'IO44':
      PIN_NUMBER='(44)';
      BIDIRECTIONAL='TRUE';
      INPUT_LOAD='(-0.01,0.01)';
      OUTPUT_LOAD='(1.0,-1.0)';
    'IO45':
      PIN_NUMBER='(45)';
      BIDIRECTIONAL='TRUE';
      INPUT_LOAD='(-0.01,0.01)';
      OUTPUT_LOAD='(1.0,-1.0)';
    'IO46':
      PIN_NUMBER='(46)';
      BIDIRECTIONAL='TRUE';
      INPUT_LOAD='(-0.01,0.01)';
      OUTPUT_LOAD='(1.0,-1.0)';
    'IO47':
      PIN_NUMBER='(47)';
      BIDIRECTIONAL='TRUE';
      INPUT_LOAD='(-0.01,0.01)';
      OUTPUT_LOAD='(1.0,-1.0)';
    'IO48':
      PIN_NUMBER='(48)';
      BIDIRECTIONAL='TRUE';
      INPUT_LOAD='(-0.01,0.01)';
      OUTPUT_LOAD='(1.0,-1.0)';
    'IO49':
      PIN_NUMBER='(49)';
      BIDIRECTIONAL='TRUE';
      INPUT_LOAD='(-0.01,0.01)';
      OUTPUT_LOAD='(1.0,-1.0)';
    'IO5':
      PIN_NUMBER='(5)';
      BIDIRECTIONAL='TRUE';
      INPUT_LOAD='(-0.01,0.01)';
      OUTPUT_LOAD='(1.0,-1.0)';
    'IO50':
      PIN_NUMBER='(50)';
      BIDIRECTIONAL='TRUE';
      INPUT_LOAD='(-0.01,0.01)';
      OUTPUT_LOAD='(1.0,-1.0)';
    'IO51':
      PIN_NUMBER='(51)';
      BIDIRECTIONAL='TRUE';
      INPUT_LOAD='(-0.01,0.01)';
      OUTPUT_LOAD='(1.0,-1.0)';
    'IO52':
      PIN_NUMBER='(52)';
      BIDIRECTIONAL='TRUE';
      INPUT_LOAD='(-0.01,0.01)';
      OUTPUT_LOAD='(1.0,-1.0)';
    'IO53':
      PIN_NUMBER='(53)';
      BIDIRECTIONAL='TRUE';
      INPUT_LOAD='(-0.01,0.01)';
      OUTPUT_LOAD='(1.0,-1.0)';
    'IO54':
      PIN_NUMBER='(54)';
      BIDIRECTIONAL='TRUE';
      INPUT_LOAD='(-0.01,0.01)';
      OUTPUT_LOAD='(1.0,-1.0)';
    'IO55':
      PIN_NUMBER='(55)';
      BIDIRECTIONAL='TRUE';
      INPUT_LOAD='(-0.01,0.01)';
      OUTPUT_LOAD='(1.0,-1.0)';
    'IO56':
      PIN_NUMBER='(56)';
      BIDIRECTIONAL='TRUE';
      INPUT_LOAD='(-0.01,0.01)';
      OUTPUT_LOAD='(1.0,-1.0)';
    'IO57':
      PIN_NUMBER='(57)';
      BIDIRECTIONAL='TRUE';
      INPUT_LOAD='(-0.01,0.01)';
      OUTPUT_LOAD='(1.0,-1.0)';
    'IO58':
      PIN_NUMBER='(58)';
      BIDIRECTIONAL='TRUE';
      INPUT_LOAD='(-0.01,0.01)';
      OUTPUT_LOAD='(1.0,-1.0)';
    'IO59':
      PIN_NUMBER='(59)';
      BIDIRECTIONAL='TRUE';
      INPUT_LOAD='(-0.01,0.01)';
      OUTPUT_LOAD='(1.0,-1.0)';
    'IO6':
      PIN_NUMBER='(6)';
      BIDIRECTIONAL='TRUE';
      INPUT_LOAD='(-0.01,0.01)';
      OUTPUT_LOAD='(1.0,-1.0)';
    'IO60':
      PIN_NUMBER='(60)';
      BIDIRECTIONAL='TRUE';
      INPUT_LOAD='(-0.01,0.01)';
      OUTPUT_LOAD='(1.0,-1.0)';
    'IO61':
      PIN_NUMBER='(61)';
      BIDIRECTIONAL='TRUE';
      INPUT_LOAD='(-0.01,0.01)';
      OUTPUT_LOAD='(1.0,-1.0)';
    'IO62':
      PIN_NUMBER='(62)';
      BIDIRECTIONAL='TRUE';
      INPUT_LOAD='(-0.01,0.01)';
      OUTPUT_LOAD='(1.0,-1.0)';
    'IO63':
      PIN_NUMBER='(63)';
      BIDIRECTIONAL='TRUE';
      INPUT_LOAD='(-0.01,0.01)';
      OUTPUT_LOAD='(1.0,-1.0)';
    'IO64':
      PIN_NUMBER='(64)';
      BIDIRECTIONAL='TRUE';
      INPUT_LOAD='(-0.01,0.01)';
      OUTPUT_LOAD='(1.0,-1.0)';
    'IO7':
      PIN_NUMBER='(7)';
      BIDIRECTIONAL='TRUE';
      INPUT_LOAD='(-0.01,0.01)';
      OUTPUT_LOAD='(1.0,-1.0)';
    'IO8':
      PIN_NUMBER='(8)';
      BIDIRECTIONAL='TRUE';
      INPUT_LOAD='(-0.01,0.01)';
      OUTPUT_LOAD='(1.0,-1.0)';
    'IO9':
      PIN_NUMBER='(9)';
      BIDIRECTIONAL='TRUE';
      INPUT_LOAD='(-0.01,0.01)';
      OUTPUT_LOAD='(1.0,-1.0)';
  end_pin;
  body
    PART_NAME='SCONN64_H87568002_A';
    PHYS_DES_PREFIX='J';
  end_body;
end_primitive;

primitive 'SCONN64_H87568002_A_SMT1';
  pin
    'EXT_MDIO_I2C_SEL':
      PIN_NUMBER='(3)';
      BIDIRECTIONAL='TRUE';
      INPUT_LOAD='(-0.01,0.01)';
      OUTPUT_LOAD='(1.0,-1.0)';
    'GND'<17>:
      PIN_NUMBER='(63)';
      PINUSE='GROUND';
      NO_LOAD_CHECK='Both';
      NO_IO_CHECK='Both';
      NO_ASSERT_CHECK='TRUE';
      NO_DIR_CHECK='TRUE';
      ALLOW_CONNECT='TRUE';
    'GND'<16>:
      PIN_NUMBER='(60)';
      PINUSE='GROUND';
      NO_LOAD_CHECK='Both';
      NO_IO_CHECK='Both';
      NO_ASSERT_CHECK='TRUE';
      NO_DIR_CHECK='TRUE';
      ALLOW_CONNECT='TRUE';
    'GND'<15>:
      PIN_NUMBER='(57)';
      PINUSE='GROUND';
      NO_LOAD_CHECK='Both';
      NO_IO_CHECK='Both';
      NO_ASSERT_CHECK='TRUE';
      NO_DIR_CHECK='TRUE';
      ALLOW_CONNECT='TRUE';
    'GND'<14>:
      PIN_NUMBER='(54)';
      PINUSE='GROUND';
      NO_LOAD_CHECK='Both';
      NO_IO_CHECK='Both';
      NO_ASSERT_CHECK='TRUE';
      NO_DIR_CHECK='TRUE';
      ALLOW_CONNECT='TRUE';
    'GND'<13>:
      PIN_NUMBER='(51)';
      PINUSE='GROUND';
      NO_LOAD_CHECK='Both';
      NO_IO_CHECK='Both';
      NO_ASSERT_CHECK='TRUE';
      NO_DIR_CHECK='TRUE';
      ALLOW_CONNECT='TRUE';
    'GND'<12>:
      PIN_NUMBER='(48)';
      PINUSE='GROUND';
      NO_LOAD_CHECK='Both';
      NO_IO_CHECK='Both';
      NO_ASSERT_CHECK='TRUE';
      NO_DIR_CHECK='TRUE';
      ALLOW_CONNECT='TRUE';
    'GND'<11>:
      PIN_NUMBER='(45)';
      PINUSE='GROUND';
      NO_LOAD_CHECK='Both';
      NO_IO_CHECK='Both';
      NO_ASSERT_CHECK='TRUE';
      NO_DIR_CHECK='TRUE';
      ALLOW_CONNECT='TRUE';
    'GND'<10>:
      PIN_NUMBER='(42)';
      PINUSE='GROUND';
      NO_LOAD_CHECK='Both';
      NO_IO_CHECK='Both';
      NO_ASSERT_CHECK='TRUE';
      NO_DIR_CHECK='TRUE';
      ALLOW_CONNECT='TRUE';
    'GND'<9>:
      PIN_NUMBER='(39)';
      PINUSE='GROUND';
      NO_LOAD_CHECK='Both';
      NO_IO_CHECK='Both';
      NO_ASSERT_CHECK='TRUE';
      NO_DIR_CHECK='TRUE';
      ALLOW_CONNECT='TRUE';
    'GND'<8>:
      PIN_NUMBER='(28)';
      PINUSE='GROUND';
      NO_LOAD_CHECK='Both';
      NO_IO_CHECK='Both';
      NO_ASSERT_CHECK='TRUE';
      NO_DIR_CHECK='TRUE';
      ALLOW_CONNECT='TRUE';
    'GND'<7>:
      PIN_NUMBER='(25)';
      PINUSE='GROUND';
      NO_LOAD_CHECK='Both';
      NO_IO_CHECK='Both';
      NO_ASSERT_CHECK='TRUE';
      NO_DIR_CHECK='TRUE';
      ALLOW_CONNECT='TRUE';
    'GND'<6>:
      PIN_NUMBER='(22)';
      PINUSE='GROUND';
      NO_LOAD_CHECK='Both';
      NO_IO_CHECK='Both';
      NO_ASSERT_CHECK='TRUE';
      NO_DIR_CHECK='TRUE';
      ALLOW_CONNECT='TRUE';
    'GND'<5>:
      PIN_NUMBER='(19)';
      PINUSE='GROUND';
      NO_LOAD_CHECK='Both';
      NO_IO_CHECK='Both';
      NO_ASSERT_CHECK='TRUE';
      NO_DIR_CHECK='TRUE';
      ALLOW_CONNECT='TRUE';
    'GND'<4>:
      PIN_NUMBER='(16)';
      PINUSE='GROUND';
      NO_LOAD_CHECK='Both';
      NO_IO_CHECK='Both';
      NO_ASSERT_CHECK='TRUE';
      NO_DIR_CHECK='TRUE';
      ALLOW_CONNECT='TRUE';
    'GND'<3>:
      PIN_NUMBER='(13)';
      PINUSE='GROUND';
      NO_LOAD_CHECK='Both';
      NO_IO_CHECK='Both';
      NO_ASSERT_CHECK='TRUE';
      NO_DIR_CHECK='TRUE';
      ALLOW_CONNECT='TRUE';
    'GND'<2>:
      PIN_NUMBER='(10)';
      PINUSE='GROUND';
      NO_LOAD_CHECK='Both';
      NO_IO_CHECK='Both';
      NO_ASSERT_CHECK='TRUE';
      NO_DIR_CHECK='TRUE';
      ALLOW_CONNECT='TRUE';
    'GND'<1>:
      PIN_NUMBER='(7)';
      PINUSE='GROUND';
      NO_LOAD_CHECK='Both';
      NO_IO_CHECK='Both';
      NO_ASSERT_CHECK='TRUE';
      NO_DIR_CHECK='TRUE';
      ALLOW_CONNECT='TRUE';
    'GND'<0>:
      PIN_NUMBER='(4)';
      PINUSE='GROUND';
      NO_LOAD_CHECK='Both';
      NO_IO_CHECK='Both';
      NO_ASSERT_CHECK='TRUE';
      NO_DIR_CHECK='TRUE';
      ALLOW_CONNECT='TRUE';
    'KR_RX_DN'<3>:
      PIN_NUMBER='(24)';
      BIDIRECTIONAL='TRUE';
      INPUT_LOAD='(-0.01,0.01)';
      OUTPUT_LOAD='(1.0,-1.0)';
    'KR_RX_DN'<2>:
      PIN_NUMBER='(18)';
      BIDIRECTIONAL='TRUE';
      INPUT_LOAD='(-0.01,0.01)';
      OUTPUT_LOAD='(1.0,-1.0)';
    'KR_RX_DN'<1>:
      PIN_NUMBER='(59)';
      BIDIRECTIONAL='TRUE';
      INPUT_LOAD='(-0.01,0.01)';
      OUTPUT_LOAD='(1.0,-1.0)';
    'KR_RX_DN'<0>:
      PIN_NUMBER='(53)';
      BIDIRECTIONAL='TRUE';
      INPUT_LOAD='(-0.01,0.01)';
      OUTPUT_LOAD='(1.0,-1.0)';
    'KR_RX_DP'<3>:
      PIN_NUMBER='(23)';
      BIDIRECTIONAL='TRUE';
      INPUT_LOAD='(-0.01,0.01)';
      OUTPUT_LOAD='(1.0,-1.0)';
    'KR_RX_DP'<2>:
      PIN_NUMBER='(17)';
      BIDIRECTIONAL='TRUE';
      INPUT_LOAD='(-0.01,0.01)';
      OUTPUT_LOAD='(1.0,-1.0)';
    'KR_RX_DP'<1>:
      PIN_NUMBER='(58)';
      BIDIRECTIONAL='TRUE';
      INPUT_LOAD='(-0.01,0.01)';
      OUTPUT_LOAD='(1.0,-1.0)';
    'KR_RX_DP'<0>:
      PIN_NUMBER='(52)';
      BIDIRECTIONAL='TRUE';
      INPUT_LOAD='(-0.01,0.01)';
      OUTPUT_LOAD='(1.0,-1.0)';
    'KR_TX_DN'<3>:
      PIN_NUMBER='(12)';
      BIDIRECTIONAL='TRUE';
      INPUT_LOAD='(-0.01,0.01)';
      OUTPUT_LOAD='(1.0,-1.0)';
    'KR_TX_DN'<2>:
      PIN_NUMBER='(6)';
      BIDIRECTIONAL='TRUE';
      INPUT_LOAD='(-0.01,0.01)';
      OUTPUT_LOAD='(1.0,-1.0)';
    'KR_TX_DN'<1>:
      PIN_NUMBER='(47)';
      BIDIRECTIONAL='TRUE';
      INPUT_LOAD='(-0.01,0.01)';
      OUTPUT_LOAD='(1.0,-1.0)';
    'KR_TX_DN'<0>:
      PIN_NUMBER='(41)';
      BIDIRECTIONAL='TRUE';
      INPUT_LOAD='(-0.01,0.01)';
      OUTPUT_LOAD='(1.0,-1.0)';
    'KR_TX_DP'<3>:
      PIN_NUMBER='(11)';
      BIDIRECTIONAL='TRUE';
      INPUT_LOAD='(-0.01,0.01)';
      OUTPUT_LOAD='(1.0,-1.0)';
    'KR_TX_DP'<2>:
      PIN_NUMBER='(5)';
      BIDIRECTIONAL='TRUE';
      INPUT_LOAD='(-0.01,0.01)';
      OUTPUT_LOAD='(1.0,-1.0)';
    'KR_TX_DP'<1>:
      PIN_NUMBER='(46)';
      BIDIRECTIONAL='TRUE';
      INPUT_LOAD='(-0.01,0.01)';
      OUTPUT_LOAD='(1.0,-1.0)';
    'KR_TX_DP'<0>:
      PIN_NUMBER='(40)';
      BIDIRECTIONAL='TRUE';
      INPUT_LOAD='(-0.01,0.01)';
      OUTPUT_LOAD='(1.0,-1.0)';
    'LED_P0_0':
      PIN_NUMBER='(43)';
      OUTPUT_LOAD='(1.0,-1.0)';
    'LED_P0_1':
      PIN_NUMBER='(44)';
      OUTPUT_LOAD='(1.0,-1.0)';
    'LED_P1_0':
      PIN_NUMBER='(8)';
      OUTPUT_LOAD='(1.0,-1.0)';
    'LED_P1_1':
      PIN_NUMBER='(9)';
      OUTPUT_LOAD='(1.0,-1.0)';
    'LED_P2_0':
      PIN_NUMBER='(14)';
      OUTPUT_LOAD='(1.0,-1.0)';
    'LED_P2_1':
      PIN_NUMBER='(15)';
      OUTPUT_LOAD='(1.0,-1.0)';
    'LED_P3_0':
      PIN_NUMBER='(55)';
      OUTPUT_LOAD='(1.0,-1.0)';
    'LED_P3_1':
      PIN_NUMBER='(56)';
      OUTPUT_LOAD='(1.0,-1.0)';
    'MEZZ_PRSNTC2_N':
      PIN_NUMBER='(64)';
      BIDIRECTIONAL='TRUE';
      INPUT_LOAD='(-0.01,0.01)';
      OUTPUT_LOAD='(1.0,-1.0)';
    'MEZZ_SMCLK':
      PIN_NUMBER='(1)';
      BIDIRECTIONAL='TRUE';
      INPUT_LOAD='(-0.01,0.01)';
      OUTPUT_LOAD='(1.0,-1.0)';
    'MEZZ_SMDATA':
      PIN_NUMBER='(2)';
      BIDIRECTIONAL='TRUE';
      INPUT_LOAD='(-0.01,0.01)';
      OUTPUT_LOAD='(1.0,-1.0)';
    'P12V/P12V_AUX/P5V_AUX'<2>:
      PIN_NUMBER='(35)';
      PINUSE='POWER';
      NO_LOAD_CHECK='Both';
      NO_IO_CHECK='Both';
      NO_ASSERT_CHECK='TRUE';
      NO_DIR_CHECK='TRUE';
      ALLOW_CONNECT='TRUE';
    'P12V/P12V_AUX/P5V_AUX'<1>:
      PIN_NUMBER='(34)';
      PINUSE='POWER';
      NO_LOAD_CHECK='Both';
      NO_IO_CHECK='Both';
      NO_ASSERT_CHECK='TRUE';
      NO_DIR_CHECK='TRUE';
      ALLOW_CONNECT='TRUE';
    'P12V/P12V_AUX/P5V_AUX'<0>:
      PIN_NUMBER='(33)';
      PINUSE='POWER';
      NO_LOAD_CHECK='Both';
      NO_IO_CHECK='Both';
      NO_ASSERT_CHECK='TRUE';
      NO_DIR_CHECK='TRUE';
      ALLOW_CONNECT='TRUE';
    'RSVD':
      PIN_NUMBER='(36)';
      PINUSE='UNSPEC';
      NO_LOAD_CHECK='Both';
      NO_IO_CHECK='Both';
      NO_ASSERT_CHECK='TRUE';
      NO_DIR_CHECK='TRUE';
      ALLOW_CONNECT='TRUE';
    'SCL0':
      PIN_NUMBER='(20)';
      BIDIRECTIONAL='TRUE';
      INPUT_LOAD='(-0.01,0.01)';
      OUTPUT_LOAD='(1.0,-1.0)';
    'SCL1':
      PIN_NUMBER='(26)';
      BIDIRECTIONAL='TRUE';
      INPUT_LOAD='(-0.01,0.01)';
      OUTPUT_LOAD='(1.0,-1.0)';
    'SCL2':
      PIN_NUMBER='(61)';
      BIDIRECTIONAL='TRUE';
      INPUT_LOAD='(-0.01,0.01)';
      OUTPUT_LOAD='(1.0,-1.0)';
    'SCL3':
      PIN_NUMBER='(29)';
      BIDIRECTIONAL='TRUE';
      INPUT_LOAD='(-0.01,0.01)';
      OUTPUT_LOAD='(1.0,-1.0)';
    'SDA0':
      PIN_NUMBER='(21)';
      BIDIRECTIONAL='TRUE';
      INPUT_LOAD='(-0.01,0.01)';
      OUTPUT_LOAD='(1.0,-1.0)';
    'SDA1':
      PIN_NUMBER='(27)';
      BIDIRECTIONAL='TRUE';
      INPUT_LOAD='(-0.01,0.01)';
      OUTPUT_LOAD='(1.0,-1.0)';
    'SDA2':
      PIN_NUMBER='(62)';
      BIDIRECTIONAL='TRUE';
      INPUT_LOAD='(-0.01,0.01)';
      OUTPUT_LOAD='(1.0,-1.0)';
    'SDA3':
      PIN_NUMBER='(30)';
      BIDIRECTIONAL='TRUE';
      INPUT_LOAD='(-0.01,0.01)';
      OUTPUT_LOAD='(1.0,-1.0)';
    'SDP0_0':
      PIN_NUMBER='(37)';
      BIDIRECTIONAL='TRUE';
      INPUT_LOAD='(-0.01,0.01)';
      OUTPUT_LOAD='(1.0,-1.0)';
    'SDP1_0':
      PIN_NUMBER='(38)';
      BIDIRECTIONAL='TRUE';
      INPUT_LOAD='(-0.01,0.01)';
      OUTPUT_LOAD='(1.0,-1.0)';
    'SDP2_0':
      PIN_NUMBER='(31)';
      BIDIRECTIONAL='TRUE';
      INPUT_LOAD='(-0.01,0.01)';
      OUTPUT_LOAD='(1.0,-1.0)';
    'SDP3_0':
      PIN_NUMBER='(32)';
      BIDIRECTIONAL='TRUE';
      INPUT_LOAD='(-0.01,0.01)';
      OUTPUT_LOAD='(1.0,-1.0)';
    'SHARED_KR_MDC_0':
      PIN_NUMBER='(49)';
      BIDIRECTIONAL='TRUE';
      INPUT_LOAD='(-0.01,0.01)';
      OUTPUT_LOAD='(1.0,-1.0)';
    'SHARED_KR_MDIO_0':
      PIN_NUMBER='(50)';
      BIDIRECTIONAL='TRUE';
      INPUT_LOAD='(-0.01,0.01)';
      OUTPUT_LOAD='(1.0,-1.0)';
  end_pin;
  body
    PART_NAME='SCONN64_H87568002_A';
    PHYS_DES_PREFIX='J';
  end_body;
end_primitive;

END.
